(kicad_pcb
	(version 20260206)
	(generator "pcbnew")
	(generator_version "10.0")
	(general
		(thickness 1.6)
		(legacy_teardrops no)
	)
	(paper "A4")
	(title_block
		(title "Bryce Canyon_IOM_IOC_16318-2_OCP.brd")
		(comment 1 "Bryce Canyon / footprints 881-887 of 1605")
	)
	(layers
		(0 "F.Cu" signal "TOP")
		(4 "In1.Cu" signal "L2GND")
		(6 "In2.Cu" signal "L3")
		(8 "In3.Cu" signal "L4VCC")
		(10 "In4.Cu" signal "L5VCC")
		(12 "In5.Cu" signal "L6")
		(14 "In6.Cu" signal "L7GND")
		(2 "B.Cu" signal "BOTTOM")
		(9 "F.Adhes" user "F.Adhesive")
		(11 "B.Adhes" user "B.Adhesive")
		(13 "F.Paste" user "Package Geometry/Pastemask Top")
		(15 "B.Paste" user "Package Geometry/Pastemask Bottom")
		(5 "F.SilkS" user "Ref Des/Silkscreen Top")
		(7 "B.SilkS" user "Ref Des/Silkscreen Bottom")
		(1 "F.Mask" user "Board Geometry/Soldermask Top")
		(3 "B.Mask" user "Board Geometry/Soldermask Bottom")
		(17 "Dwgs.User" user "User.Drawings")
		(19 "Cmts.User" user "User.Comments")
		(21 "Eco1.User" user "User.Eco1")
		(23 "Eco2.User" user "User.Eco2")
		(25 "Edge.Cuts" user "Board Geometry/Outline")
		(27 "Margin" user)
		(31 "F.CrtYd" user "Package Geometry/Place Bound Top")
		(29 "B.CrtYd" user "Package Geometry/Place Bound Bottom")
		(35 "F.Fab" user "Ref Des/Assembly Top")
		(33 "B.Fab" user "Ref Des/Assembly Bottom")
	)
	(footprint ""
		(layer "F.Cu")
		(at 44.714414 -125.91034 -90)
		(property "Reference" "R89"
			(at 0 0 270)
			(layer "F.SilkS")
			(hide yes)
			(effects
				(font
					(size 1.27 1.27)
				)
			)
		)
		(property "Value" "33D2R2F-GP"
			(at 0.064008 -3.993896 270)
			(unlocked yes)
			(layer "F.Fab")
			(hide yes)
			(effects
				(font
					(size 1.016 1.016)
					(thickness 0.1524)
				)
			)
		)
		(property "Device Type" "R402H16"
			(at 0.064008 -5.517896 270)
			(unlocked yes)
			(layer "F.Fab")
			(hide yes)
			(effects
				(font
					(size 1.016 1.016)
					(thickness 0.1524)
				)
			)
		)
		(duplicate_pad_numbers_are_jumpers no)
		(fp_line
			(start -0.508 -0.9398)
			(end -0.508 0.9398)
			(stroke
				(width 0.1524)
				(type default)
			)
			(layer "F.SilkS")
		)
		(fp_line
			(start 0.508 -0.9398)
			(end -0.508 -0.9398)
			(stroke
				(width 0.1524)
				(type default)
			)
			(layer "F.SilkS")
		)
		(fp_rect
			(start -0.508 0.9398)
			(end 0.508 -0.9398)
			(stroke
				(width 0)
				(type default)
			)
			(fill no)
			(layer "F.CrtYd")
		)
		(fp_rect
			(start -0.508 0.9398)
			(end 0.508 -0.9398)
			(stroke
				(width 0)
				(type default)
			)
			(fill no)
			(layer "F.Fab")
		)
		(pad "1" smd custom
			(at 0 -0.4445 270)
			(size 0.1397 0.1397)
			(layers "F.Cu" "F.Mask" "F.Paste")
			(net "BMC_SPI_MISO")
			(options
				(clearance outline)
				(anchor circle)
			)
			(primitives
				(gr_poly
					(pts
						(arc
							(start -0.1778 -0.2794)
							(mid -0.249642 -0.249642)
							(end -0.2794 -0.1778)
						)
						(arc
							(start -0.2794 0.1778)
							(mid -0.249642 0.249642)
							(end -0.1778 0.2794)
						)
						(arc
							(start 0.1778 0.2794)
							(mid 0.249642 0.249642)
							(end 0.2794 0.1778)
						)
						(arc
							(start 0.2794 -0.1778)
							(mid 0.249642 -0.249642)
							(end 0.1778 -0.2794)
						)
					)
					(width 0)
					(fill yes)
				)
			)
		)
		(pad "2" smd custom
			(at 0 0.4445 270)
			(size 0.1397 0.1397)
			(layers "F.Cu" "F.Mask" "F.Paste")
			(net "BMC_SPI_MISO_TPM")
			(options
				(clearance outline)
				(anchor circle)
			)
			(primitives
				(gr_poly
					(pts
						(arc
							(start -0.1778 -0.2794)
							(mid -0.249642 -0.249642)
							(end -0.2794 -0.1778)
						)
						(arc
							(start -0.2794 0.1778)
							(mid -0.249642 0.249642)
							(end -0.1778 0.2794)
						)
						(arc
							(start 0.1778 0.2794)
							(mid 0.249642 0.249642)
							(end 0.2794 0.1778)
						)
						(arc
							(start 0.2794 -0.1778)
							(mid 0.249642 -0.249642)
							(end 0.1778 -0.2794)
						)
					)
					(width 0)
					(fill yes)
				)
			)
		)
	)
	(footprint ""
		(layer "F.Cu")
		(at 84.184744 -167.69842)
		(property "Reference" "Q12"
			(at 0 0 0)
			(layer "F.SilkS")
			(hide yes)
			(effects
				(font
					(size 1.27 1.27)
				)
			)
		)
		(property "Value" "2N7002K-1-GP"
			(at 0.127 -8.9662 0)
			(unlocked yes)
			(layer "F.Fab")
			(hide yes)
			(effects
				(font
					(size 1.016 1.016)
					(thickness 0.1524)
				)
			)
		)
		(property "Device Type" "SOT23DGS2D4H44"
			(at 0.127 -10.4902 0)
			(unlocked yes)
			(layer "F.Fab")
			(hide yes)
			(effects
				(font
					(size 1.016 1.016)
					(thickness 0.1524)
				)
			)
		)
		(duplicate_pad_numbers_are_jumpers no)
		(fp_line
			(start -1.651 -1.778)
			(end -1.651 1.778)
			(stroke
				(width 0.1524)
				(type default)
			)
			(layer "F.SilkS")
		)
		(fp_line
			(start -1.651 1.778)
			(end 1.651 1.778)
			(stroke
				(width 0.1524)
				(type default)
			)
			(layer "F.SilkS")
		)
		(fp_line
			(start 1.651 -1.778)
			(end -1.651 -1.778)
			(stroke
				(width 0.1524)
				(type default)
			)
			(layer "F.SilkS")
		)
		(fp_line
			(start 1.651 1.778)
			(end 1.651 -1.778)
			(stroke
				(width 0.1524)
				(type default)
			)
			(layer "F.SilkS")
		)
		(fp_poly
			(pts
				(xy -1.778 1.8796) (xy -1.778 -1.8796) (xy 1.778 -1.8796) (xy 1.778 1.8796)
			)
			(stroke
				(width 0)
				(type default)
			)
			(fill no)
			(layer "F.CrtYd")
		)
		(fp_poly
			(pts
				(xy -1.778 1.8796) (xy -1.778 -1.8796) (xy 1.778 -1.8796) (xy 1.778 1.8796)
			)
			(stroke
				(width 0)
				(type default)
			)
			(fill no)
			(layer "F.Fab")
		)
		(pad "D" smd custom
			(at 0 -0.9525)
			(size 0.1905 0.1905)
			(layers "F.Cu" "F.Mask" "F.Paste")
			(net "IOM_STBY_PGOOD")
			(options
				(clearance outline)
				(anchor circle)
			)
			(primitives
				(gr_poly
					(pts
						(arc
							(start -0.1778 0.5715)
							(mid -0.321484 0.511984)
							(end -0.381 0.3683)
						)
						(arc
							(start -0.381 -0.3683)
							(mid -0.321484 -0.511984)
							(end -0.1778 -0.5715)
						)
						(arc
							(start 0.1778 -0.5715)
							(mid 0.321484 -0.511984)
							(end 0.381 -0.3683)
						)
						(arc
							(start 0.381 0.3683)
							(mid 0.321484 0.511984)
							(end 0.1778 0.5715)
						)
					)
					(width 0)
					(fill yes)
				)
			)
		)
		(pad "G" smd custom
			(at -0.98425 0.9525)
			(size 0.1905 0.1905)
			(layers "F.Cu" "F.Mask" "F.Paste")
			(net "P1V15_STBY_PG_G")
			(options
				(clearance outline)
				(anchor circle)
			)
			(primitives
				(gr_poly
					(pts
						(arc
							(start -0.1778 0.5715)
							(mid -0.321484 0.511984)
							(end -0.381 0.3683)
						)
						(arc
							(start -0.381 -0.3683)
							(mid -0.321484 -0.511984)
							(end -0.1778 -0.5715)
						)
						(arc
							(start 0.1778 -0.5715)
							(mid 0.321484 -0.511984)
							(end 0.381 -0.3683)
						)
						(arc
							(start 0.381 0.3683)
							(mid 0.321484 0.511984)
							(end 0.1778 0.5715)
						)
					)
					(width 0)
					(fill yes)
				)
			)
		)
		(pad "S" smd custom
			(at 0.98425 0.9525)
			(size 0.1905 0.1905)
			(layers "F.Cu" "F.Mask" "F.Paste")
			(net "GND")
			(options
				(clearance outline)
				(anchor circle)
			)
			(primitives
				(gr_poly
					(pts
						(arc
							(start -0.1778 0.5715)
							(mid -0.321484 0.511984)
							(end -0.381 0.3683)
						)
						(arc
							(start -0.381 -0.3683)
							(mid -0.321484 -0.511984)
							(end -0.1778 -0.5715)
						)
						(arc
							(start 0.1778 -0.5715)
							(mid 0.321484 -0.511984)
							(end 0.381 -0.3683)
						)
						(arc
							(start 0.381 0.3683)
							(mid 0.321484 0.511984)
							(end 0.1778 0.5715)
						)
					)
					(width 0)
					(fill yes)
				)
			)
		)
	)
	(footprint ""
		(layer "F.Cu")
		(at 48.101504 -161.180272 180)
		(property "Reference" "R204"
			(at 0 0 180)
			(layer "F.SilkS")
			(hide yes)
			(effects
				(font
					(size 1.27 1.27)
				)
			)
		)
		(property "Value" "2K2R2F-GP"
			(at 0.064008 -3.993896 180)
			(unlocked yes)
			(layer "F.Fab")
			(hide yes)
			(effects
				(font
					(size 1.016 1.016)
					(thickness 0.1524)
				)
			)
		)
		(property "Device Type" "R402H16"
			(at 0.064008 -5.517896 180)
			(unlocked yes)
			(layer "F.Fab")
			(hide yes)
			(effects
				(font
					(size 1.016 1.016)
					(thickness 0.1524)
				)
			)
		)
		(duplicate_pad_numbers_are_jumpers no)
		(fp_line
			(start 0.508 -0.9398)
			(end -0.508 -0.9398)
			(stroke
				(width 0.1524)
				(type default)
			)
			(layer "F.SilkS")
		)
		(fp_line
			(start -0.508 -0.9398)
			(end -0.508 0.9398)
			(stroke
				(width 0.1524)
				(type default)
			)
			(layer "F.SilkS")
		)
		(fp_rect
			(start -0.508 0.9398)
			(end 0.508 -0.9398)
			(stroke
				(width 0)
				(type default)
			)
			(fill no)
			(layer "F.CrtYd")
		)
		(fp_rect
			(start -0.508 0.9398)
			(end 0.508 -0.9398)
			(stroke
				(width 0)
				(type default)
			)
			(fill no)
			(layer "F.Fab")
		)
		(pad "1" smd custom
			(at 0 -0.4445 180)
			(size 0.1397 0.1397)
			(layers "F.Cu" "F.Mask" "F.Paste")
			(net "I2C_DPB_MISC_SDA_OUT")
			(options
				(clearance outline)
				(anchor circle)
			)
			(primitives
				(gr_poly
					(pts
						(arc
							(start -0.1778 -0.2794)
							(mid -0.249642 -0.249642)
							(end -0.2794 -0.1778)
						)
						(arc
							(start -0.2794 0.1778)
							(mid -0.249642 0.249642)
							(end -0.1778 0.2794)
						)
						(arc
							(start 0.1778 0.2794)
							(mid 0.249642 0.249642)
							(end 0.2794 0.1778)
						)
						(arc
							(start 0.2794 -0.1778)
							(mid 0.249642 -0.249642)
							(end 0.1778 -0.2794)
						)
					)
					(width 0)
					(fill yes)
				)
			)
		)
		(pad "2" smd custom
			(at 0 0.4445 180)
			(size 0.1397 0.1397)
			(layers "F.Cu" "F.Mask" "F.Paste")
			(net "P3V3_STBY")
			(options
				(clearance outline)
				(anchor circle)
			)
			(primitives
				(gr_poly
					(pts
						(arc
							(start -0.1778 -0.2794)
							(mid -0.249642 -0.249642)
							(end -0.2794 -0.1778)
						)
						(arc
							(start -0.2794 0.1778)
							(mid -0.249642 0.249642)
							(end -0.1778 0.2794)
						)
						(arc
							(start 0.1778 0.2794)
							(mid 0.249642 0.249642)
							(end 0.2794 0.1778)
						)
						(arc
							(start 0.2794 -0.1778)
							(mid 0.249642 -0.249642)
							(end 0.1778 -0.2794)
						)
					)
					(width 0)
					(fill yes)
				)
			)
		)
	)
	(footprint ""
		(layer "F.Cu")
		(at 222.50019 -14.99997)
		(property "Reference" ""
			(at 0 0 0)
			(layer "F.SilkS")
			(hide yes)
			(effects
				(font
					(size 1.27 1.27)
				)
			)
		)
		(property "Value" "*"
			(at 6.2484 0.3429 0)
			(unlocked yes)
			(layer "F.Fab")
			(hide yes)
			(effects
				(font
					(size 1.016 1.016)
					(thickness 0.1524)
				)
			)
		)
		(duplicate_pad_numbers_are_jumpers no)
		(fp_poly
			(pts
				(arc
					(start 5.0673 0)
					(mid -5.0673 0)
					(end 5.0673 0)
				)
			)
			(stroke
				(width 0)
				(type default)
			)
			(fill no)
			(layer "B.CrtYd")
		)
		(fp_poly
			(pts
				(arc
					(start 5.0673 0)
					(mid -5.0673 0)
					(end 5.0673 0)
				)
			)
			(stroke
				(width 0)
				(type default)
			)
			(fill no)
			(layer "F.CrtYd")
		)
		(fp_poly
			(pts
				(arc
					(start 5.0673 0)
					(mid -5.0673 0)
					(end 5.0673 0)
				)
			)
			(stroke
				(width 0)
				(type default)
			)
			(fill no)
			(layer "B.Fab")
		)
		(fp_poly
			(pts
				(arc
					(start 5.0673 0)
					(mid -5.0673 0)
					(end 5.0673 0)
				)
			)
			(stroke
				(width 0)
				(type default)
			)
			(fill no)
			(layer "F.Fab")
		)
		(pad "1" thru_hole circle
			(at 0 0)
			(size 9.525 9.525)
			(drill 4.0132)
			(layers "*.Cu" "*.Mask")
			(remove_unused_layers no)
			(net "Net_71")
			(clearance -2.2479)
			(thermal_gap 0.3048)
			(padstack
				(mode front_inner_back)
				(layer "Inner"
					(shape circle)
					(size 4.4196 4.4196)
					(clearance 0.3048)
				)
				(layer "B.Cu"
					(shape circle)
					(size 9.525 9.525)
					(clearance -2.2479)
				)
			)
		)
	)
	(footprint ""
		(layer "F.Cu")
		(at 175.5648 -77.8002 180)
		(property "Reference" "TP133"
			(at 0 0 180)
			(layer "F.SilkS")
			(hide yes)
			(effects
				(font
					(size 1.27 1.27)
				)
			)
		)
		(property "Value" "TPAD28-2-GP"
			(at -0.0127 -1.6637 180)
			(unlocked yes)
			(layer "F.Fab")
			(hide yes)
			(effects
				(font
					(size 1.016 1.016)
					(thickness 0.1524)
				)
			)
		)
		(property "Device Type" "TPAD28"
			(at -0.0127 -3.1877 180)
			(unlocked yes)
			(layer "F.Fab")
			(hide yes)
			(effects
				(font
					(size 1.016 1.016)
					(thickness 0.1524)
				)
			)
		)
		(duplicate_pad_numbers_are_jumpers no)
		(fp_poly
			(pts
				(arc
					(start -0.3556 0)
					(mid 0.3556 0)
					(end -0.3556 0)
				)
			)
			(stroke
				(width 0)
				(type default)
			)
			(fill no)
			(layer "F.CrtYd")
		)
		(fp_poly
			(pts
				(arc
					(start -0.6096 0)
					(mid 0.6096 0)
					(end -0.6096 0)
				)
			)
			(stroke
				(width 0)
				(type default)
			)
			(fill no)
			(layer "F.Fab")
		)
		(pad "1" smd circle
			(at 0 0 180)
			(size 0.7112 0.7112)
			(layers "F.Cu" "F.Mask" "F.Paste")
			(net "UART_SERCLK")
		)
	)
	(footprint ""
		(layer "F.Cu")
		(at 156.474668 -90.021664)
		(property "Reference" "U44"
			(at 0 0 0)
			(layer "F.SilkS")
			(hide yes)
			(effects
				(font
					(size 1.27 1.27)
				)
			)
		)
		(property "Value" "TXS0102DCUR-1-GP"
			(at 0 -11.1252 0)
			(unlocked yes)
			(layer "F.Fab")
			(hide yes)
			(effects
				(font
					(size 1.016 1.016)
					(thickness 0.1524)
				)
			)
		)
		(property "Device Type" "SSOIC8-4H36"
			(at 0 -12.6492 0)
			(unlocked yes)
			(layer "F.Fab")
			(hide yes)
			(effects
				(font
					(size 1.016 1.016)
					(thickness 0.1524)
				)
			)
		)
		(duplicate_pad_numbers_are_jumpers no)
		(fp_line
			(start -1.2954 0.4572)
			(end -1.2954 2.159)
			(stroke
				(width 0.4064)
				(type default)
			)
			(layer "F.SilkS")
		)
		(fp_line
			(start -1.2573 -2.1844)
			(end 1.2573 -2.1844)
			(stroke
				(width 0.1524)
				(type default)
			)
			(layer "F.SilkS")
		)
		(fp_line
			(start -1.2573 -0.3556)
			(end -1.2192 -0.3556)
			(stroke
				(width 0.1524)
				(type default)
			)
			(layer "F.SilkS")
		)
		(fp_line
			(start -1.2573 2.1844)
			(end -1.2573 -2.1844)
			(stroke
				(width 0.1524)
				(type default)
			)
			(layer "F.SilkS")
		)
		(fp_line
			(start -1.2192 -0.3556)
			(end -0.9017 -0.0381)
			(stroke
				(width 0.1524)
				(type default)
			)
			(layer "F.SilkS")
		)
		(fp_line
			(start -1.2065 0.2667)
			(end -1.27 0.2667)
			(stroke
				(width 0.1524)
				(type default)
			)
			(layer "F.SilkS")
		)
		(fp_line
			(start -0.9017 -0.0381)
			(end -1.2065 0.2667)
			(stroke
				(width 0.1524)
				(type default)
			)
			(layer "F.SilkS")
		)
		(fp_line
			(start 1.2573 -2.1844)
			(end 1.2573 2.1844)
			(stroke
				(width 0.1524)
				(type default)
			)
			(layer "F.SilkS")
		)
		(fp_line
			(start 1.2573 2.1844)
			(end -1.2573 2.1844)
			(stroke
				(width 0.1524)
				(type default)
			)
			(layer "F.SilkS")
		)
		(fp_poly
			(pts
				(xy -1.5113 2.4384) (xy 1.5113 2.4384) (xy 1.5113 -2.4384) (xy -1.5113 -2.4384)
			)
			(stroke
				(width 0)
				(type default)
			)
			(fill no)
			(layer "F.CrtYd")
		)
		(fp_poly
			(pts
				(xy -1.5113 -2.4384) (xy 1.5113 -2.4384) (xy 1.5113 2.4384) (xy -1.5113 2.4384)
			)
			(stroke
				(width 0)
				(type default)
			)
			(fill no)
			(layer "F.Fab")
		)
		(pad "1" smd rect
			(at -0.75057 1.1684)
			(size 0.3048 1.524)
			(layers "F.Cu" "F.Mask" "F.Paste")
			(net "IOC_UART_R_RX")
		)
		(pad "2" smd rect
			(at -0.25019 1.1684)
			(size 0.3048 1.524)
			(layers "F.Cu" "F.Mask" "F.Paste")
			(net "GND")
		)
		(pad "3" smd rect
			(at 0.25019 1.1684)
			(size 0.3048 1.524)
			(layers "F.Cu" "F.Mask" "F.Paste")
			(net "P1V8")
		)
		(pad "4" smd rect
			(at 0.75057 1.1684)
			(size 0.3048 1.524)
			(layers "F.Cu" "F.Mask" "F.Paste")
			(net "IOC_UART_0_RX_R")
		)
		(pad "5" smd rect
			(at 0.75057 -1.1684)
			(size 0.3048 1.524)
			(layers "F.Cu" "F.Mask" "F.Paste")
			(net "IOC_UART_0_TX_R")
		)
		(pad "6" smd rect
			(at 0.25019 -1.1684)
			(size 0.3048 1.524)
			(layers "F.Cu" "F.Mask" "F.Paste")
			(net "SYS_RST_N_0")
		)
		(pad "7" smd rect
			(at -0.25019 -1.1684)
			(size 0.3048 1.524)
			(layers "F.Cu" "F.Mask" "F.Paste")
			(net "P3V3")
		)
		(pad "8" smd rect
			(at -0.75057 -1.1684)
			(size 0.3048 1.524)
			(layers "F.Cu" "F.Mask" "F.Paste")
			(net "IOC_UART_R_TX")
		)
	)
	(footprint ""
		(layer "F.Cu")
		(at 59.8424 -155.3972)
		(property "Reference" "TP50"
			(at 0 0 0)
			(layer "F.SilkS")
			(hide yes)
			(effects
				(font
					(size 1.27 1.27)
				)
			)
		)
		(property "Value" "TPAD28-2-GP"
			(at -0.0127 -1.6637 0)
			(unlocked yes)
			(layer "F.Fab")
			(hide yes)
			(effects
				(font
					(size 1.016 1.016)
					(thickness 0.1524)
				)
			)
		)
		(property "Device Type" "TPAD28"
			(at -0.0127 -3.1877 0)
			(unlocked yes)
			(layer "F.Fab")
			(hide yes)
			(effects
				(font
					(size 1.016 1.016)
					(thickness 0.1524)
				)
			)
		)
		(duplicate_pad_numbers_are_jumpers no)
		(fp_poly
			(pts
				(arc
					(start 0.3556 0)
					(mid -0.3556 0)
					(end 0.3556 0)
				)
			)
			(stroke
				(width 0)
				(type default)
			)
			(fill no)
			(layer "F.CrtYd")
		)
		(fp_poly
			(pts
				(arc
					(start 0.6096 0)
					(mid -0.6096 0)
					(end 0.6096 0)
				)
			)
			(stroke
				(width 0)
				(type default)
			)
			(fill no)
			(layer "F.Fab")
		)
		(pad "1" smd circle
			(at 0 0)
			(size 0.7112 0.7112)
			(layers "F.Cu" "F.Mask" "F.Paste")
			(net "TP_BMC_GPIOT0")
		)
	)
)
